(kicad_pcb
	(version 20260206)
	(generator "pcbnew")
	(generator_version "10.0")
	(general
		(thickness 1.6)
		(legacy_teardrops no)
	)
	(paper "A4")
	(title_block
		(title "Wiwynn_Tioga_Pass_MB.brd")
		(comment 1 "Tioga Pass / footprint 2254 of 4770 (U5D1), pads 193-302 of 3647")
	)
	(layers
		(0 "F.Cu" signal "TOP")
		(4 "In1.Cu" signal "L2GND")
		(6 "In2.Cu" signal "L3")
		(8 "In3.Cu" signal "L4GND")
		(10 "In4.Cu" signal "L5")
		(12 "In5.Cu" signal "L6GND")
		(14 "In6.Cu" signal "L7VCC")
		(16 "In7.Cu" signal "L8VCC")
		(18 "In8.Cu" signal "L9GND")
		(20 "In9.Cu" signal "L10")
		(22 "In10.Cu" signal "L11GND")
		(24 "In11.Cu" signal "L12")
		(26 "In12.Cu" signal "L13GND")
		(2 "B.Cu" signal "BOTTOM")
		(9 "F.Adhes" user "F.Adhesive")
		(11 "B.Adhes" user "B.Adhesive")
		(13 "F.Paste" user "Package Geometry/Pastemask Top")
		(15 "B.Paste" user "Package Geometry/Pastemask Bottom")
		(5 "F.SilkS" user "Ref Des/Silkscreen Top")
		(7 "B.SilkS" user "Ref Des/Silkscreen Bottom")
		(1 "F.Mask" user "Board Geometry/Soldermask Top")
		(3 "B.Mask" user "Board Geometry/Soldermask Bottom")
		(17 "Dwgs.User" user "User.Drawings")
		(19 "Cmts.User" user "User.Comments")
		(21 "Eco1.User" user "User.Eco1")
		(23 "Eco2.User" user "User.Eco2")
		(25 "Edge.Cuts" user "Board Geometry/Outline")
		(27 "Margin" user)
		(31 "F.CrtYd" user "Package Geometry/Place Bound Top")
		(29 "B.CrtYd" user "Package Geometry/Place Bound Bottom")
		(35 "F.Fab" user "Ref Des/Assembly Top")
		(33 "B.Fab" user "Ref Des/Assembly Bottom")
	)
	(footprint ""
		(layer "F.Cu")
		(at 270.000222 -76.550012 180)
		(property "Reference" "U5D1"
			(at 19.124422 31.601918 0)
			(unlocked yes)
			(layer "F.SilkS")
			(effects
				(font
					(size 0.7874 0.5842)
					(thickness 0.1524)
				)
			)
		)
		(property "Value" ""
			(at 0 0 180)
			(layer "F.Fab")
			(effects
				(font
					(size 1.27 1.27)
				)
			)
		)
		(duplicate_pad_numbers_are_jumpers no)
		(pad "AE12" smd circle
			(at -27.806904 -13.215874)
			(size 0.4318 0.4318)
			(layers "F.Cu" "F.Mask" "F.Paste")
			(net "XDP_CPU_OBSFN_B0_MBP6_N")
		)
		(pad "AE14" smd circle
			(at -26.090118 -13.215874)
			(size 0.4318 0.4318)
			(layers "F.Cu" "F.Mask" "F.Paste")
			(net "XDP_CPU0_TDO")
		)
		(pad "AE16" smd circle
			(at -24.373078 -13.215874)
			(size 0.4318 0.4318)
			(layers "F.Cu" "F.Mask" "F.Paste")
			(net "GND")
		)
		(pad "AE18" smd circle
			(at -22.656038 -13.215874)
			(size 0.4318 0.4318)
			(layers "F.Cu" "F.Mask" "F.Paste")
			(net "SMB_DDR_DEF_SCL_G_R")
		)
		(pad "AE20" smd circle
			(at -20.938998 -13.215874)
			(size 0.4318 0.4318)
			(layers "F.Cu" "F.Mask" "F.Paste")
			(net "PU_CPU0_LEGACY_SKT")
		)
		(pad "AE22" smd circle
			(at -19.221958 -13.215874)
			(size 0.4318 0.4318)
			(layers "F.Cu" "F.Mask" "F.Paste")
			(net "M_C_DQ<58>")
		)
		(pad "AE24" smd circle
			(at -17.504918 -13.215874)
			(size 0.4318 0.4318)
			(layers "F.Cu" "F.Mask" "F.Paste")
			(net "M_C_DQS_DP<16>")
		)
		(pad "AE26" smd circle
			(at -15.787878 -13.215874)
			(size 0.4318 0.4318)
			(layers "F.Cu" "F.Mask" "F.Paste")
			(net "M_C_DQ<60>")
		)
		(pad "AE28" smd circle
			(at -14.071092 -13.215874)
			(size 0.4318 0.4318)
			(layers "F.Cu" "F.Mask" "F.Paste")
			(net "M_C_DQ<50>")
		)
		(pad "AE30" smd circle
			(at -12.354052 -13.215874)
			(size 0.4318 0.4318)
			(layers "F.Cu" "F.Mask" "F.Paste")
			(net "M_C_DQS_DP<15>")
		)
		(pad "AE32" smd circle
			(at -10.637012 -13.215874)
			(size 0.4318 0.4318)
			(layers "F.Cu" "F.Mask" "F.Paste")
			(net "M_C_DQ<52>")
		)
		(pad "AE34" smd circle
			(at -8.919972 -13.215874)
			(size 0.4318 0.4318)
			(layers "F.Cu" "F.Mask" "F.Paste")
			(net "PVCCIO_CPU0")
		)
		(pad "AE36" smd circle
			(at -7.202932 -13.215874)
			(size 0.4318 0.4318)
			(layers "F.Cu" "F.Mask" "F.Paste")
			(net "PVCCIO_CPU0")
		)
		(pad "AE38" smd circle
			(at -5.485892 -13.215874)
			(size 0.4318 0.4318)
			(layers "F.Cu" "F.Mask" "F.Paste")
			(net "GND")
		)
		(pad "AE40" smd circle
			(at -3.769106 -13.215874)
			(size 0.4318 0.4318)
			(layers "F.Cu" "F.Mask" "F.Paste")
			(net "GND")
		)
		(pad "AE42" smd circle
			(at -2.052066 -13.215874)
			(size 0.4318 0.4318)
			(layers "F.Cu" "F.Mask" "F.Paste")
			(net "GND")
		)
		(pad "AE46" smd circle
			(at 2.910586 -15.015972)
			(size 0.4318 0.4318)
			(layers "F.Cu" "F.Mask" "F.Paste")
			(net "TP_CPU0_RSVD_251")
		)
		(pad "AE48" smd circle
			(at 4.627626 -15.015972)
			(size 0.4318 0.4318)
			(layers "F.Cu" "F.Mask" "F.Paste")
			(net "TP_CPU0_RSVD_250")
		)
		(pad "AE50" smd circle
			(at 6.344412 -15.015972)
			(size 0.4318 0.4318)
			(layers "F.Cu" "F.Mask" "F.Paste")
			(net "TP_CPU0_RSVD_249")
		)
		(pad "AE52" smd circle
			(at 8.061452 -15.015972)
			(size 0.4318 0.4318)
			(layers "F.Cu" "F.Mask" "F.Paste")
			(net "TP_CPU0_RSVD_248")
		)
		(pad "AE54" smd circle
			(at 9.778492 -15.015972)
			(size 0.4318 0.4318)
			(layers "F.Cu" "F.Mask" "F.Paste")
			(net "M_C_MA<15>")
		)
		(pad "AE56" smd circle
			(at 11.495532 -15.015972)
			(size 0.4318 0.4318)
			(layers "F.Cu" "F.Mask" "F.Paste")
			(net "M_C_BA<1>")
		)
		(pad "AE58" smd circle
			(at 13.212572 -15.015972)
			(size 0.4318 0.4318)
			(layers "F.Cu" "F.Mask" "F.Paste")
			(net "M_C_MA<1>")
		)
		(pad "AE60" smd circle
			(at 14.929612 -15.015972)
			(size 0.4318 0.4318)
			(layers "F.Cu" "F.Mask" "F.Paste")
			(net "M_C_MA<7>")
		)
		(pad "AE62" smd circle
			(at 16.646398 -15.015972)
			(size 0.4318 0.4318)
			(layers "F.Cu" "F.Mask" "F.Paste")
			(net "M_C_BG<1>")
		)
		(pad "AE64" smd circle
			(at 18.363438 -15.015972)
			(size 0.4318 0.4318)
			(layers "F.Cu" "F.Mask" "F.Paste")
			(net "GND")
		)
		(pad "AE66" smd circle
			(at 20.080478 -15.015972)
			(size 0.4318 0.4318)
			(layers "F.Cu" "F.Mask" "F.Paste")
			(net "GND")
		)
		(pad "AE68" smd circle
			(at 21.797518 -15.015972)
			(size 0.4318 0.4318)
			(layers "F.Cu" "F.Mask" "F.Paste")
			(net "GND")
		)
		(pad "AE70" smd circle
			(at 23.514558 -15.015972)
			(size 0.4318 0.4318)
			(layers "F.Cu" "F.Mask" "F.Paste")
			(net "GND")
		)
		(pad "AE72" smd circle
			(at 25.231598 -15.015972)
			(size 0.4318 0.4318)
			(layers "F.Cu" "F.Mask" "F.Paste")
			(net "TP_CPU0_RSVD_247")
		)
		(pad "AE74" smd circle
			(at 26.948384 -15.015972)
			(size 0.4318 0.4318)
			(layers "F.Cu" "F.Mask" "F.Paste")
			(net "M_C_DQ<13>")
		)
		(pad "AE76" smd circle
			(at 28.665424 -15.015972)
			(size 0.4318 0.4318)
			(layers "F.Cu" "F.Mask" "F.Paste")
			(net "M_C_DQ<8>")
		)
		(pad "AE78" smd circle
			(at 30.382464 -15.015972)
			(size 0.4318 0.4318)
			(layers "F.Cu" "F.Mask" "F.Paste")
			(net "GND")
		)
		(pad "AE80" smd circle
			(at 32.099504 -15.015972)
			(size 0.4318 0.4318)
			(layers "F.Cu" "F.Mask" "F.Paste")
			(net "M_B_DQS_DP<1>")
		)
		(pad "AE82" smd circle
			(at 33.816544 -15.015972)
			(size 0.4318 0.4318)
			(layers "F.Cu" "F.Mask" "F.Paste")
			(net "M_B_DQ<14>")
		)
		(pad "AE84" smd circle
			(at 35.533584 -15.015972)
			(size 0.4318 0.4318)
			(layers "F.Cu" "F.Mask" "F.Paste")
			(net "M_A_DQ<3>")
		)
		(pad "AE86" smd custom
			(at 37.250624 -15.015972 270)
			(size 0.10795 0.10795)
			(layers "F.Cu" "F.Mask" "F.Paste")
			(net "M_A_DQ<2>")
			(options
				(clearance outline)
				(anchor circle)
			)
			(primitives
				(gr_poly
					(pts
						(arc
							(start 0.2159 -0.0381)
							(mid 0 -0.254)
							(end -0.2159 -0.0381)
						)
						(arc
							(start -0.2159 0.0381)
							(mid 0 0.254)
							(end 0.2159 0.0381)
						)
					)
					(width 0)
					(fill yes)
				)
			)
		)
		(pad "AF1" smd custom
			(at -37.250624 -12.720828 90)
			(size 0.10795 0.10795)
			(layers "F.Cu" "F.Mask" "F.Paste")
			(net "GND")
			(options
				(clearance outline)
				(anchor circle)
			)
			(primitives
				(gr_poly
					(pts
						(arc
							(start 0.2159 -0.0381)
							(mid 0 -0.254)
							(end -0.2159 -0.0381)
						)
						(arc
							(start -0.2159 0.0381)
							(mid 0 0.254)
							(end 0.2159 0.0381)
						)
					)
					(width 0)
					(fill yes)
				)
			)
		)
		(pad "AF3" smd circle
			(at -35.533584 -12.720828)
			(size 0.4318 0.4318)
			(layers "F.Cu" "F.Mask" "F.Paste")
			(net "UPI_CPU0_CPU1_P0P0_DP<13>")
		)
		(pad "AF5" smd circle
			(at -33.816544 -12.720828)
			(size 0.4318 0.4318)
			(layers "F.Cu" "F.Mask" "F.Paste")
			(net "PVCCIO_CPU0")
		)
		(pad "AF7" smd circle
			(at -32.099504 -12.720828)
			(size 0.4318 0.4318)
			(layers "F.Cu" "F.Mask" "F.Paste")
			(net "UPI_CPU1_CPU0_P0P0_DP<14>")
		)
		(pad "AF9" smd circle
			(at -30.382464 -12.720828)
			(size 0.4318 0.4318)
			(layers "F.Cu" "F.Mask" "F.Paste")
			(net "GND")
		)
		(pad "AF11" smd circle
			(at -28.665424 -12.720828)
			(size 0.4318 0.4318)
			(layers "F.Cu" "F.Mask" "F.Paste")
			(net "TP_XDP_CPU0_OBSDATA_A1_MBP3_N")
		)
		(pad "AF13" smd circle
			(at -26.948384 -12.720828)
			(size 0.4318 0.4318)
			(layers "F.Cu" "F.Mask" "F.Paste")
			(net "H_CPU0_MEMDEF_MEMHOT_G_N")
		)
		(pad "AF15" smd circle
			(at -25.231598 -12.720828)
			(size 0.4318 0.4318)
			(layers "F.Cu" "F.Mask" "F.Paste")
			(net "H_CPU0_FAST_WAKE_N")
		)
		(pad "AF17" smd circle
			(at -23.514558 -12.720828)
			(size 0.4318 0.4318)
			(layers "F.Cu" "F.Mask" "F.Paste")
			(net "SMB_DDR_ABC_SDA_G_R")
		)
		(pad "AF19" smd circle
			(at -21.797518 -12.720828)
			(size 0.4318 0.4318)
			(layers "F.Cu" "F.Mask" "F.Paste")
			(net "TP_CPU0_RSVD_246")
		)
		(pad "AF21" smd circle
			(at -20.080478 -12.720828)
			(size 0.4318 0.4318)
			(layers "F.Cu" "F.Mask" "F.Paste")
			(net "GND")
		)
		(pad "AF23" smd circle
			(at -18.363438 -12.720828)
			(size 0.4318 0.4318)
			(layers "F.Cu" "F.Mask" "F.Paste")
			(net "GND")
		)
		(pad "AF25" smd circle
			(at -16.646398 -12.720828)
			(size 0.4318 0.4318)
			(layers "F.Cu" "F.Mask" "F.Paste")
			(net "GND")
		)
		(pad "AF27" smd circle
			(at -14.929612 -12.720828)
			(size 0.4318 0.4318)
			(layers "F.Cu" "F.Mask" "F.Paste")
			(net "GND")
		)
		(pad "AF29" smd circle
			(at -13.212572 -12.720828)
			(size 0.4318 0.4318)
			(layers "F.Cu" "F.Mask" "F.Paste")
			(net "GND")
		)
		(pad "AF31" smd circle
			(at -11.495532 -12.720828)
			(size 0.4318 0.4318)
			(layers "F.Cu" "F.Mask" "F.Paste")
			(net "GND")
		)
		(pad "AF33" smd circle
			(at -9.778492 -12.720828)
			(size 0.4318 0.4318)
			(layers "F.Cu" "F.Mask" "F.Paste")
			(net "GND")
		)
		(pad "AF35" smd circle
			(at -8.061452 -12.720828)
			(size 0.4318 0.4318)
			(layers "F.Cu" "F.Mask" "F.Paste")
			(net "PVCCIO_CPU0")
		)
		(pad "AF37" smd circle
			(at -6.344412 -12.720828)
			(size 0.4318 0.4318)
			(layers "F.Cu" "F.Mask" "F.Paste")
			(net "GND")
		)
		(pad "AF39" smd circle
			(at -4.627626 -12.720828)
			(size 0.4318 0.4318)
			(layers "F.Cu" "F.Mask" "F.Paste")
			(net "GND")
		)
		(pad "AF41" smd circle
			(at -2.910586 -12.720828)
			(size 0.4318 0.4318)
			(layers "F.Cu" "F.Mask" "F.Paste")
			(net "GND")
		)
		(pad "AF43" smd circle
			(at -1.193546 -12.720828)
			(size 0.4318 0.4318)
			(layers "F.Cu" "F.Mask" "F.Paste")
			(net "PVCCIN_CPU0")
		)
		(pad "AF45" smd circle
			(at 2.052066 -14.520926)
			(size 0.508 0.508)
			(layers "F.Cu" "F.Mask" "F.Paste")
			(net "PD_CPU0_RSVD_TEST_1")
		)
		(pad "AF47" smd circle
			(at 3.769106 -14.520926)
			(size 0.4318 0.4318)
			(layers "F.Cu" "F.Mask" "F.Paste")
			(net "TP_CPU0_RSVD_245")
		)
		(pad "AF49" smd circle
			(at 5.485892 -14.520926)
			(size 0.4318 0.4318)
			(layers "F.Cu" "F.Mask" "F.Paste")
			(net "TP_CPU0_RSVD_244")
		)
		(pad "AF51" smd circle
			(at 7.202932 -14.520926)
			(size 0.4318 0.4318)
			(layers "F.Cu" "F.Mask" "F.Paste")
			(net "TP_CPU0_RSVD_243")
		)
		(pad "AF53" smd circle
			(at 8.919972 -14.520926)
			(size 0.4318 0.4318)
			(layers "F.Cu" "F.Mask" "F.Paste")
			(net "TP_CPU0_RSVD_242")
		)
		(pad "AF55" smd circle
			(at 10.637012 -14.520926)
			(size 0.4318 0.4318)
			(layers "F.Cu" "F.Mask" "F.Paste")
			(net "PVDDQ_ABC")
		)
		(pad "AF57" smd circle
			(at 12.354052 -14.520926)
			(size 0.4318 0.4318)
			(layers "F.Cu" "F.Mask" "F.Paste")
			(net "PVDDQ_ABC")
		)
		(pad "AF59" smd circle
			(at 14.071092 -14.520926)
			(size 0.4318 0.4318)
			(layers "F.Cu" "F.Mask" "F.Paste")
			(net "PVDDQ_ABC")
		)
		(pad "AF61" smd circle
			(at 15.787878 -14.520926)
			(size 0.4318 0.4318)
			(layers "F.Cu" "F.Mask" "F.Paste")
			(net "PVDDQ_ABC")
		)
		(pad "AF63" smd circle
			(at 17.504918 -14.520926)
			(size 0.4318 0.4318)
			(layers "F.Cu" "F.Mask" "F.Paste")
			(net "PVDDQ_ABC")
		)
		(pad "AF65" smd circle
			(at 19.221958 -14.520926)
			(size 0.4318 0.4318)
			(layers "F.Cu" "F.Mask" "F.Paste")
			(net "M_A_ECC<3>")
		)
		(pad "AF67" smd circle
			(at 20.938998 -14.520926)
			(size 0.4318 0.4318)
			(layers "F.Cu" "F.Mask" "F.Paste")
			(net "M_A_DQS_DP<8>")
		)
		(pad "AF69" smd circle
			(at 22.656038 -14.520926)
			(size 0.4318 0.4318)
			(layers "F.Cu" "F.Mask" "F.Paste")
			(net "M_A_ECC<5>")
		)
		(pad "AF71" smd circle
			(at 24.373078 -14.520926)
			(size 0.4318 0.4318)
			(layers "F.Cu" "F.Mask" "F.Paste")
			(net "TP_CPU0_RSVD_241")
		)
		(pad "AF73" smd circle
			(at 26.090118 -14.520926)
			(size 0.4318 0.4318)
			(layers "F.Cu" "F.Mask" "F.Paste")
			(net "GND")
		)
		(pad "AF75" smd circle
			(at 27.806904 -14.520926)
			(size 0.4318 0.4318)
			(layers "F.Cu" "F.Mask" "F.Paste")
			(net "M_C_DQ<12>")
		)
		(pad "AF77" smd circle
			(at 29.523944 -14.520926)
			(size 0.4318 0.4318)
			(layers "F.Cu" "F.Mask" "F.Paste")
			(net "GND")
		)
		(pad "AF79" smd circle
			(at 31.240984 -14.520926)
			(size 0.4318 0.4318)
			(layers "F.Cu" "F.Mask" "F.Paste")
			(net "M_B_DQ<9>")
		)
		(pad "AF81" smd circle
			(at 32.958024 -14.520926)
			(size 0.4318 0.4318)
			(layers "F.Cu" "F.Mask" "F.Paste")
			(net "M_B_DQS_DP<10>")
		)
		(pad "AF83" smd circle
			(at 34.675064 -14.520926)
			(size 0.4318 0.4318)
			(layers "F.Cu" "F.Mask" "F.Paste")
			(net "GND")
		)
		(pad "AF85" smd circle
			(at 36.392104 -14.520926)
			(size 0.4318 0.4318)
			(layers "F.Cu" "F.Mask" "F.Paste")
			(net "GND")
		)
		(pad "AG2" smd circle
			(at -36.392104 -12.225274)
			(size 0.4318 0.4318)
			(layers "F.Cu" "F.Mask" "F.Paste")
			(net "UPI_CPU0_CPU1_P0P0_DP<12>")
		)
		(pad "AG4" smd circle
			(at -34.675064 -12.225274)
			(size 0.4318 0.4318)
			(layers "F.Cu" "F.Mask" "F.Paste")
			(net "UPI_CPU0_CPU1_P0P0_DN<13>")
		)
		(pad "AG6" smd circle
			(at -32.958024 -12.225274)
			(size 0.4318 0.4318)
			(layers "F.Cu" "F.Mask" "F.Paste")
			(net "UPI_CPU1_CPU0_P0P0_DP<15>")
		)
		(pad "AG8" smd circle
			(at -31.240984 -12.225274)
			(size 0.4318 0.4318)
			(layers "F.Cu" "F.Mask" "F.Paste")
			(net "UPI_CPU1_CPU0_P0P0_DN<14>")
		)
		(pad "AG10" smd circle
			(at -29.523944 -12.225274)
			(size 0.4318 0.4318)
			(layers "F.Cu" "F.Mask" "F.Paste")
			(net "TP_XDP_CPU0_OBSDATA_A0_MBP2_N")
		)
		(pad "AG12" smd circle
			(at -27.806904 -12.225274)
			(size 0.4318 0.4318)
			(layers "F.Cu" "F.Mask" "F.Paste")
			(net "GND")
		)
		(pad "AG14" smd circle
			(at -26.090118 -12.225274)
			(size 0.4318 0.4318)
			(layers "F.Cu" "F.Mask" "F.Paste")
			(net "GND")
		)
		(pad "AG16" smd circle
			(at -24.373078 -12.225274)
			(size 0.4318 0.4318)
			(layers "F.Cu" "F.Mask" "F.Paste")
			(net "XDP_CPU_PRDY_N")
		)
		(pad "AG18" smd circle
			(at -22.656038 -12.225274)
			(size 0.4318 0.4318)
			(layers "F.Cu" "F.Mask" "F.Paste")
			(net "GND")
		)
		(pad "AG20" smd circle
			(at -20.938998 -12.225274)
			(size 0.4318 0.4318)
			(layers "F.Cu" "F.Mask" "F.Paste")
			(net "TP_CPU0_RSVD_240")
		)
		(pad "AG22" smd circle
			(at -19.221958 -12.225274)
			(size 0.4318 0.4318)
			(layers "F.Cu" "F.Mask" "F.Paste")
			(net "M_C_DQ<59>")
		)
		(pad "AG24" smd circle
			(at -17.504918 -12.225274)
			(size 0.4318 0.4318)
			(layers "F.Cu" "F.Mask" "F.Paste")
			(net "M_C_DQS_DP<7>")
		)
		(pad "AG26" smd circle
			(at -15.787878 -12.225274)
			(size 0.4318 0.4318)
			(layers "F.Cu" "F.Mask" "F.Paste")
			(net "M_C_DQ<61>")
		)
		(pad "AG28" smd circle
			(at -14.071092 -12.225274)
			(size 0.4318 0.4318)
			(layers "F.Cu" "F.Mask" "F.Paste")
			(net "M_C_DQ<51>")
		)
		(pad "AG30" smd circle
			(at -12.354052 -12.225274)
			(size 0.4318 0.4318)
			(layers "F.Cu" "F.Mask" "F.Paste")
			(net "M_C_DQS_DP<6>")
		)
		(pad "AG32" smd circle
			(at -10.637012 -12.225274)
			(size 0.4318 0.4318)
			(layers "F.Cu" "F.Mask" "F.Paste")
			(net "M_C_DQ<53>")
		)
		(pad "AG34" smd circle
			(at -8.919972 -12.225274)
			(size 0.4318 0.4318)
			(layers "F.Cu" "F.Mask" "F.Paste")
			(net "PVCCIO_CPU0")
		)
		(pad "AG36" smd circle
			(at -7.202932 -12.225274)
			(size 0.4318 0.4318)
			(layers "F.Cu" "F.Mask" "F.Paste")
			(net "GND")
		)
		(pad "AG38" smd circle
			(at -5.485892 -12.225274)
			(size 0.4318 0.4318)
			(layers "F.Cu" "F.Mask" "F.Paste")
			(net "PVCCIN_CPU0")
		)
		(pad "AG40" smd circle
			(at -3.769106 -12.225274)
			(size 0.4318 0.4318)
			(layers "F.Cu" "F.Mask" "F.Paste")
			(net "PVCCIN_CPU0")
		)
		(pad "AG42" smd circle
			(at -2.052066 -12.225274)
			(size 0.4318 0.4318)
			(layers "F.Cu" "F.Mask" "F.Paste")
			(net "PVCCIN_CPU0")
		)
		(pad "AG46" smd circle
			(at 2.910586 -14.025372)
			(size 0.4318 0.4318)
			(layers "F.Cu" "F.Mask" "F.Paste")
			(net "PD_CPU0_RSVD_TEST_2")
		)
		(pad "AG48" smd circle
			(at 4.627626 -14.025372)
			(size 0.4318 0.4318)
			(layers "F.Cu" "F.Mask" "F.Paste")
			(net "TP_CPU0_RSVD_239")
		)
		(pad "AG50" smd circle
			(at 6.344412 -14.025372)
			(size 0.4318 0.4318)
			(layers "F.Cu" "F.Mask" "F.Paste")
			(net "TP_CPU0_RSVD_238")
		)
		(pad "AG52" smd circle
			(at 8.061452 -14.025372)
			(size 0.4318 0.4318)
			(layers "F.Cu" "F.Mask" "F.Paste")
			(net "TP_CPU0_RSVD_237")
		)
		(pad "AG54" smd circle
			(at 9.778492 -14.025372)
			(size 0.4318 0.4318)
			(layers "F.Cu" "F.Mask" "F.Paste")
			(net "TP_CPU0_RSVD_236")
		)
		(pad "AG56" smd circle
			(at 11.495532 -14.025372)
			(size 0.4318 0.4318)
			(layers "F.Cu" "F.Mask" "F.Paste")
			(net "TP_CPU0_RSVD_235")
		)
		(pad "AG58" smd circle
			(at 13.212572 -14.025372)
			(size 0.4318 0.4318)
			(layers "F.Cu" "F.Mask" "F.Paste")
			(net "M_C_MA<9>")
		)
		(pad "AG60" smd circle
			(at 14.929612 -14.025372)
			(size 0.4318 0.4318)
			(layers "F.Cu" "F.Mask" "F.Paste")
			(net "M_C_MA<11>")
		)
		(pad "AG62" smd circle
			(at 16.646398 -14.025372)
			(size 0.4318 0.4318)
			(layers "F.Cu" "F.Mask" "F.Paste")
			(net "M_C_MA<12>")
		)
	)
)
